(kicad_pcb
	(version 20260206)
	(generator "pcbnew")
	(generator_version "10.0")
	(general
		(thickness 1.6)
		(legacy_teardrops no)
	)
	(paper "A4")
	(title_block
		(title "panther-plus-userver — 13130-1b_20150205.brd")
		(comment 1 "Honey Badger (Wiwynn) / footprints 1335-1341 of 1509")
	)
	(layers
		(0 "F.Cu" signal "TOP")
		(4 "In1.Cu" signal "L2")
		(6 "In2.Cu" signal "L3")
		(8 "In3.Cu" signal "L4")
		(10 "In4.Cu" signal "L5")
		(12 "In5.Cu" signal "L6")
		(14 "In6.Cu" signal "L7")
		(16 "In7.Cu" signal "L8")
		(18 "In8.Cu" signal "L9")
		(20 "In9.Cu" signal "L10")
		(22 "In10.Cu" signal "L11")
		(2 "B.Cu" signal "BOTTOM")
		(9 "F.Adhes" user "F.Adhesive")
		(11 "B.Adhes" user "B.Adhesive")
		(13 "F.Paste" user "Package Geometry/Pastemask Top")
		(15 "B.Paste" user "Package Geometry/Pastemask Bottom")
		(5 "F.SilkS" user "Ref Des/Silkscreen Top")
		(7 "B.SilkS" user "Ref Des/Silkscreen Bottom")
		(1 "F.Mask" user "Board Geometry/Soldermask Top")
		(3 "B.Mask" user "Board Geometry/Soldermask Bottom")
		(17 "Dwgs.User" user "User.Drawings")
		(19 "Cmts.User" user "User.Comments")
		(21 "Eco1.User" user "User.Eco1")
		(23 "Eco2.User" user "User.Eco2")
		(25 "Edge.Cuts" user "Board Geometry/Outline")
		(27 "Margin" user)
		(31 "F.CrtYd" user "Package Geometry/Place Bound Top")
		(29 "B.CrtYd" user "Package Geometry/Place Bound Bottom")
		(35 "F.Fab" user "Ref Des/Assembly Top")
		(33 "B.Fab" user "Ref Des/Assembly Bottom")
	)
	(footprint ""
		(layer "B.Cu")
		(at 70.358 -20.066 180)
		(property "Reference" "PU13"
			(at 0 0 0)
			(layer "B.SilkS")
			(hide yes)
			(effects
				(font
					(size 1.27 1.27)
				)
				(justify mirror)
			)
		)
		(property "Value" "EP53F8QI-T-GP"
			(at -2.827274 -2.223262 180)
			(unlocked yes)
			(layer "B.Fab")
			(hide yes)
			(effects
				(font
					(size 1.016 1.016)
					(thickness 0.1524)
				)
				(justify mirror)
			)
		)
		(property "Device Type" "QFN16G3H46"
			(at -2.827274 -3.747262 180)
			(unlocked yes)
			(layer "B.Fab")
			(hide yes)
			(effects
				(font
					(size 1.016 1.016)
					(thickness 0.1524)
				)
				(justify mirror)
			)
		)
		(duplicate_pad_numbers_are_jumpers no)
		(fp_poly
			(pts
				(xy -1.819656 -2.195576) (xy -1.506728 -1.882648) (xy -1.1938 -2.195576)
			)
			(stroke
				(width 0)
				(type default)
			)
			(fill yes)
			(layer "B.SilkS")
		)
		(fp_rect
			(start 1.8796 1.8796)
			(end -1.8796 -1.8796)
			(stroke
				(width 0)
				(type default)
			)
			(fill no)
			(layer "B.CrtYd")
		)
		(fp_rect
			(start 1.8796 1.8796)
			(end -1.8796 -1.8796)
			(stroke
				(width 0)
				(type default)
			)
			(fill no)
			(layer "B.Fab")
		)
		(pad "1" smd rect
			(at -1.249934 -1.32207)
			(size 0.3048 0.8636)
			(layers "B.Cu" "B.Mask" "B.Paste")
			(net "Net_641")
		)
		(pad "2" smd rect
			(at -0.750062 -1.32207)
			(size 0.3048 0.8636)
			(layers "B.Cu" "B.Mask" "B.Paste")
			(net "GND")
		)
		(pad "3" smd rect
			(at -0.249936 -1.32207)
			(size 0.3048 0.8636)
			(layers "B.Cu" "B.Mask" "B.Paste")
			(net "GND")
		)
		(pad "4" smd rect
			(at 0.249936 -1.32207)
			(size 0.3048 0.8636)
			(layers "B.Cu" "B.Mask" "B.Paste")
			(net "VR_AVIN_P1V8_STBY")
		)
		(pad "5" smd rect
			(at 0.750062 -1.32207)
			(size 0.3048 0.8636)
			(layers "B.Cu" "B.Mask" "B.Paste")
			(net "VR_FB_P1V8_STBY")
		)
		(pad "6" smd rect
			(at 1.249934 -1.32207)
			(size 0.3048 0.8636)
			(layers "B.Cu" "B.Mask" "B.Paste")
			(net "Net_644")
		)
		(pad "7" smd rect
			(at 1.32207 -0.249936)
			(size 0.8636 0.3048)
			(layers "B.Cu" "B.Mask" "B.Paste")
			(net "P1V8_STBY_VOUT")
		)
		(pad "8" smd rect
			(at 1.32207 0.249936)
			(size 0.8636 0.3048)
			(layers "B.Cu" "B.Mask" "B.Paste")
			(net "P1V8_STBY_VOUT")
		)
		(pad "9" smd rect
			(at 1.249934 1.32207)
			(size 0.3048 0.8636)
			(layers "B.Cu" "B.Mask" "B.Paste")
			(net "AGND_P1V8_STBY")
		)
		(pad "10" smd rect
			(at 0.750062 1.32207)
			(size 0.3048 0.8636)
			(layers "B.Cu" "B.Mask" "B.Paste")
			(net "VR_AVIN_P1V8_STBY")
		)
		(pad "11" smd rect
			(at 0.249936 1.32207)
			(size 0.3048 0.8636)
			(layers "B.Cu" "B.Mask" "B.Paste")
			(net "P1V8_STBY_PG")
		)
		(pad "12" smd rect
			(at -0.249936 1.32207)
			(size 0.3048 0.8636)
			(layers "B.Cu" "B.Mask" "B.Paste")
			(net "VR_EN_P1V8_STBY")
		)
		(pad "13" smd rect
			(at -0.750062 1.32207)
			(size 0.3048 0.8636)
			(layers "B.Cu" "B.Mask" "B.Paste")
			(net "VR_PVIN_P1V8_STBY")
		)
		(pad "14" smd rect
			(at -1.249934 1.32207)
			(size 0.3048 0.8636)
			(layers "B.Cu" "B.Mask" "B.Paste")
			(net "VR_PVIN_P1V8_STBY")
		)
		(pad "15" smd rect
			(at -1.32207 0.249936)
			(size 0.8636 0.3048)
			(layers "B.Cu" "B.Mask" "B.Paste")
			(net "Net_642")
		)
		(pad "16" smd rect
			(at -1.32207 -0.249936)
			(size 0.8636 0.3048)
			(layers "B.Cu" "B.Mask" "B.Paste")
			(net "Net_643")
		)
	)
	(footprint ""
		(layer "B.Cu")
		(at 78.232 -13.462)
		(property "Reference" "C276"
			(at 0 0 0)
			(layer "B.SilkS")
			(hide yes)
			(effects
				(font
					(size 1.27 1.27)
				)
				(justify mirror)
			)
		)
		(property "Value" "SCD1U16V2KX-3GP"
			(at -1.1811 -2.7051 0)
			(unlocked yes)
			(layer "B.Fab")
			(hide yes)
			(effects
				(font
					(size 1.016 1.016)
					(thickness 0.1524)
				)
				(justify mirror)
			)
		)
		(property "Device Type" "C402H22"
			(at -1.1811 -4.2291 0)
			(unlocked yes)
			(layer "B.Fab")
			(hide yes)
			(effects
				(font
					(size 1.016 1.016)
					(thickness 0.1524)
				)
				(justify mirror)
			)
		)
		(duplicate_pad_numbers_are_jumpers no)
		(fp_rect
			(start 0.381 0.7366)
			(end -0.381 -0.7366)
			(stroke
				(width 0)
				(type default)
			)
			(fill no)
			(layer "B.CrtYd")
		)
		(fp_rect
			(start 0.381 0.7366)
			(end -0.381 -0.7366)
			(stroke
				(width 0)
				(type default)
			)
			(fill no)
			(layer "B.Fab")
		)
		(pad "1" smd custom
			(at 0 -0.4572 180)
			(size 0.1143 0.1143)
			(layers "B.Cu" "B.Mask" "B.Paste")
			(net "P2E_CPU_SAS_C_TX_DP1")
			(options
				(clearance outline)
				(anchor circle)
			)
			(primitives
				(gr_poly
					(pts
						(arc
							(start -0.254 0.1778)
							(mid -0.239121 0.213721)
							(end -0.2032 0.2286)
						)
						(arc
							(start 0.2032 0.2286)
							(mid 0.239121 0.213721)
							(end 0.254 0.1778)
						)
						(arc
							(start 0.254 -0.1778)
							(mid 0.239121 -0.213721)
							(end 0.2032 -0.2286)
						)
						(arc
							(start -0.2032 -0.2286)
							(mid -0.239121 -0.213721)
							(end -0.254 -0.1778)
						)
					)
					(width 0)
					(fill yes)
				)
			)
		)
		(pad "2" smd custom
			(at 0 0.4572 180)
			(size 0.1143 0.1143)
			(layers "B.Cu" "B.Mask" "B.Paste")
			(net "P2E_CPU_SAS_TX_DP1")
			(options
				(clearance outline)
				(anchor circle)
			)
			(primitives
				(gr_poly
					(pts
						(arc
							(start -0.254 0.1778)
							(mid -0.239121 0.213721)
							(end -0.2032 0.2286)
						)
						(arc
							(start 0.2032 0.2286)
							(mid 0.239121 0.213721)
							(end 0.254 0.1778)
						)
						(arc
							(start 0.254 -0.1778)
							(mid 0.239121 -0.213721)
							(end 0.2032 -0.2286)
						)
						(arc
							(start -0.2032 -0.2286)
							(mid -0.239121 -0.213721)
							(end -0.254 -0.1778)
						)
					)
					(width 0)
					(fill yes)
				)
			)
		)
	)
	(footprint ""
		(layer "B.Cu")
		(at 44.1452 -16.7894)
		(property "Reference" "R351"
			(at 0 0 0)
			(layer "B.SilkS")
			(hide yes)
			(effects
				(font
					(size 1.27 1.27)
				)
				(justify mirror)
			)
		)
		(property "Value" "33R2F-3-GP"
			(at -0.064008 -3.993896 0)
			(unlocked yes)
			(layer "B.Fab")
			(hide yes)
			(effects
				(font
					(size 1.016 1.016)
					(thickness 0.1524)
				)
				(justify mirror)
			)
		)
		(property "Device Type" "R402H16"
			(at -0.064008 -5.517896 0)
			(unlocked yes)
			(layer "B.Fab")
			(hide yes)
			(effects
				(font
					(size 1.016 1.016)
					(thickness 0.1524)
				)
				(justify mirror)
			)
		)
		(duplicate_pad_numbers_are_jumpers no)
		(fp_rect
			(start 0.381 0.8382)
			(end -0.381 -0.8382)
			(stroke
				(width 0)
				(type default)
			)
			(fill no)
			(layer "B.CrtYd")
		)
		(fp_rect
			(start 0.381 0.8382)
			(end -0.381 -0.8382)
			(stroke
				(width 0)
				(type default)
			)
			(fill no)
			(layer "B.Fab")
		)
		(pad "1" smd custom
			(at 0 -0.4318 180)
			(size 0.127 0.127)
			(layers "B.Cu" "B.Mask" "B.Paste")
			(net "CLK_100M_CLKBUFF_ENET_R_DP")
			(options
				(clearance outline)
				(anchor circle)
			)
			(primitives
				(gr_poly
					(pts
						(arc
							(start -0.2032 0.2794)
							(mid -0.239121 0.264521)
							(end -0.254 0.2286)
						)
						(arc
							(start -0.254 -0.2286)
							(mid -0.239121 -0.264521)
							(end -0.2032 -0.2794)
						)
						(arc
							(start 0.2032 -0.2794)
							(mid 0.239121 -0.264521)
							(end 0.254 -0.2286)
						)
						(arc
							(start 0.254 0.2286)
							(mid 0.239121 0.264521)
							(end 0.2032 0.2794)
						)
					)
					(width 0)
					(fill yes)
				)
			)
		)
		(pad "2" smd custom
			(at 0 0.4318 180)
			(size 0.127 0.127)
			(layers "B.Cu" "B.Mask" "B.Paste")
			(net "CLK_100M_CLKBUFF_ENET_DP")
			(options
				(clearance outline)
				(anchor circle)
			)
			(primitives
				(gr_poly
					(pts
						(arc
							(start -0.2032 0.2794)
							(mid -0.239121 0.264521)
							(end -0.254 0.2286)
						)
						(arc
							(start -0.254 -0.2286)
							(mid -0.239121 -0.264521)
							(end -0.2032 -0.2794)
						)
						(arc
							(start 0.2032 -0.2794)
							(mid 0.239121 -0.264521)
							(end 0.254 -0.2286)
						)
						(arc
							(start 0.254 0.2286)
							(mid 0.239121 0.264521)
							(end 0.2032 0.2794)
						)
					)
					(width 0)
					(fill yes)
				)
			)
		)
	)
	(footprint ""
		(layer "B.Cu")
		(at 74.549 -21.9964 -90)
		(property "Reference" "PR173"
			(at 0 0 90)
			(layer "B.SilkS")
			(hide yes)
			(effects
				(font
					(size 1.27 1.27)
				)
				(justify mirror)
			)
		)
		(property "Value" "0R3J-6-GP"
			(at 0.0254 -2.0193 270)
			(unlocked yes)
			(layer "B.Fab")
			(hide yes)
			(effects
				(font
					(size 1.016 1.016)
					(thickness 0.1524)
				)
				(justify mirror)
			)
		)
		(property "Device Type" "R603H22"
			(at 0.0254 -3.5433 270)
			(unlocked yes)
			(layer "B.Fab")
			(hide yes)
			(effects
				(font
					(size 1.016 1.016)
					(thickness 0.1524)
				)
				(justify mirror)
			)
		)
		(duplicate_pad_numbers_are_jumpers no)
		(fp_line
			(start -0.4318 0)
			(end -0.2032 0)
			(stroke
				(width 0.2032)
				(type default)
			)
			(layer "B.SilkS")
		)
		(fp_line
			(start 0.2032 0)
			(end 0.4191 0)
			(stroke
				(width 0.2032)
				(type default)
			)
			(layer "B.SilkS")
		)
		(fp_rect
			(start 0.635 1.1811)
			(end -0.635 -1.1811)
			(stroke
				(width 0)
				(type default)
			)
			(fill no)
			(layer "B.CrtYd")
		)
		(fp_rect
			(start 0.635 1.1811)
			(end -0.635 -1.1811)
			(stroke
				(width 0)
				(type default)
			)
			(fill no)
			(layer "B.Fab")
		)
		(pad "1" smd custom
			(at 0 -0.6604 90)
			(size 0.19685 0.19685)
			(layers "B.Cu" "B.Mask" "B.Paste")
			(net "P3V3_STBY")
			(options
				(clearance outline)
				(anchor circle)
			)
			(primitives
				(gr_poly
					(pts
						(arc
							(start 0.508 0.2921)
							(mid 0.478242 0.363942)
							(end 0.4064 0.3937)
						)
						(arc
							(start -0.4064 0.3937)
							(mid -0.478242 0.363942)
							(end -0.508 0.2921)
						)
						(arc
							(start -0.508 -0.2921)
							(mid -0.478242 -0.363942)
							(end -0.4064 -0.3937)
						)
						(arc
							(start 0.4064 -0.3937)
							(mid 0.478242 -0.363942)
							(end 0.508 -0.2921)
						)
					)
					(width 0)
					(fill yes)
				)
			)
		)
		(pad "2" smd custom
			(at 0 0.6604 90)
			(size 0.19685 0.19685)
			(layers "B.Cu" "B.Mask" "B.Paste")
			(net "VR_PVIN_P1V8_STBY")
			(options
				(clearance outline)
				(anchor circle)
			)
			(primitives
				(gr_poly
					(pts
						(arc
							(start 0.508 0.2921)
							(mid 0.478242 0.363942)
							(end 0.4064 0.3937)
						)
						(arc
							(start -0.4064 0.3937)
							(mid -0.478242 0.363942)
							(end -0.508 0.2921)
						)
						(arc
							(start -0.508 -0.2921)
							(mid -0.478242 -0.363942)
							(end -0.4064 -0.3937)
						)
						(arc
							(start 0.4064 -0.3937)
							(mid 0.478242 -0.363942)
							(end 0.508 -0.2921)
						)
					)
					(width 0)
					(fill yes)
				)
			)
		)
	)
	(footprint ""
		(layer "B.Cu")
		(at 203.4794 -56.4642 90)
		(property "Reference" "PC160"
			(at 0 0 90)
			(layer "B.SilkS")
			(hide yes)
			(effects
				(font
					(size 1.27 1.27)
				)
				(justify mirror)
			)
		)
		(property "Value" "SC22U6D3V5MX-2GP"
			(at 0 -4.9022 90)
			(unlocked yes)
			(layer "B.Fab")
			(hide yes)
			(effects
				(font
					(size 1.016 1.016)
					(thickness 0.1524)
				)
				(justify mirror)
			)
		)
		(property "Device Type" "C805H58"
			(at 0 -6.8072 90)
			(unlocked yes)
			(layer "B.Fab")
			(hide yes)
			(effects
				(font
					(size 1.016 1.016)
					(thickness 0.1524)
				)
				(justify mirror)
			)
		)
		(duplicate_pad_numbers_are_jumpers no)
		(fp_line
			(start -0.6096 0)
			(end 0.6096 0)
			(stroke
				(width 0.3048)
				(type default)
			)
			(layer "B.SilkS")
		)
		(fp_poly
			(pts
				(xy 0.9017 1.4351) (xy -0.9017 1.4351) (xy -0.9017 -1.4351) (xy 0.9017 -1.4351)
			)
			(stroke
				(width 0)
				(type default)
			)
			(fill no)
			(layer "B.CrtYd")
		)
		(fp_poly
			(pts
				(xy -0.9017 1.4351) (xy -0.9017 -1.4351) (xy 0.9017 -1.4351) (xy 0.9017 1.4351)
			)
			(stroke
				(width 0)
				(type default)
			)
			(fill no)
			(layer "B.Fab")
		)
		(pad "1" smd rect
			(at 0 -0.8382 270)
			(size 1.5494 0.9398)
			(layers "B.Cu" "B.Mask" "B.Paste")
			(net "PV_VDDR")
		)
		(pad "2" smd rect
			(at 0 0.8382 270)
			(size 1.5494 0.9398)
			(layers "B.Cu" "B.Mask" "B.Paste")
			(net "GND")
		)
	)
	(footprint ""
		(layer "B.Cu")
		(at 99.06 -43.18)
		(property "Reference" "C156"
			(at 0 0 0)
			(layer "B.SilkS")
			(hide yes)
			(effects
				(font
					(size 1.27 1.27)
				)
				(justify mirror)
			)
		)
		(property "Value" "SC1U10V2KX-1GP"
			(at -1.1811 -2.7051 0)
			(unlocked yes)
			(layer "B.Fab")
			(hide yes)
			(effects
				(font
					(size 1.016 1.016)
					(thickness 0.1524)
				)
				(justify mirror)
			)
		)
		(property "Device Type" "C402H22"
			(at -1.1811 -4.2291 0)
			(unlocked yes)
			(layer "B.Fab")
			(hide yes)
			(effects
				(font
					(size 1.016 1.016)
					(thickness 0.1524)
				)
				(justify mirror)
			)
		)
		(duplicate_pad_numbers_are_jumpers no)
		(fp_rect
			(start 0.381 0.7366)
			(end -0.381 -0.7366)
			(stroke
				(width 0)
				(type default)
			)
			(fill no)
			(layer "B.CrtYd")
		)
		(fp_rect
			(start 0.381 0.7366)
			(end -0.381 -0.7366)
			(stroke
				(width 0)
				(type default)
			)
			(fill no)
			(layer "B.Fab")
		)
		(pad "1" smd custom
			(at 0 -0.4572 180)
			(size 0.1143 0.1143)
			(layers "B.Cu" "B.Mask" "B.Paste")
			(net "VCCCLKDDR0")
			(options
				(clearance outline)
				(anchor circle)
			)
			(primitives
				(gr_poly
					(pts
						(arc
							(start -0.254 0.1778)
							(mid -0.239121 0.213721)
							(end -0.2032 0.2286)
						)
						(arc
							(start 0.2032 0.2286)
							(mid 0.239121 0.213721)
							(end 0.254 0.1778)
						)
						(arc
							(start 0.254 -0.1778)
							(mid 0.239121 -0.213721)
							(end 0.2032 -0.2286)
						)
						(arc
							(start -0.2032 -0.2286)
							(mid -0.239121 -0.213721)
							(end -0.254 -0.1778)
						)
					)
					(width 0)
					(fill yes)
				)
			)
		)
		(pad "2" smd custom
			(at 0 0.4572 180)
			(size 0.1143 0.1143)
			(layers "B.Cu" "B.Mask" "B.Paste")
			(net "GND")
			(options
				(clearance outline)
				(anchor circle)
			)
			(primitives
				(gr_poly
					(pts
						(arc
							(start -0.254 0.1778)
							(mid -0.239121 0.213721)
							(end -0.2032 0.2286)
						)
						(arc
							(start 0.2032 0.2286)
							(mid 0.239121 0.213721)
							(end 0.254 0.1778)
						)
						(arc
							(start 0.254 -0.1778)
							(mid 0.239121 -0.213721)
							(end 0.2032 -0.2286)
						)
						(arc
							(start -0.2032 -0.2286)
							(mid -0.239121 -0.213721)
							(end -0.254 -0.1778)
						)
					)
					(width 0)
					(fill yes)
				)
			)
		)
	)
	(footprint ""
		(layer "B.Cu")
		(at 74.041 -37.465 90)
		(property "Reference" "R94"
			(at 0 0 90)
			(layer "B.SilkS")
			(hide yes)
			(effects
				(font
					(size 1.27 1.27)
				)
				(justify mirror)
			)
		)
		(property "Value" "10KR2F-2-GP"
			(at -0.064008 -3.993896 90)
			(unlocked yes)
			(layer "B.Fab")
			(hide yes)
			(effects
				(font
					(size 1.016 1.016)
					(thickness 0.1524)
				)
				(justify mirror)
			)
		)
		(property "Device Type" "R402H16"
			(at -0.064008 -5.517896 90)
			(unlocked yes)
			(layer "B.Fab")
			(hide yes)
			(effects
				(font
					(size 1.016 1.016)
					(thickness 0.1524)
				)
				(justify mirror)
			)
		)
		(duplicate_pad_numbers_are_jumpers no)
		(fp_rect
			(start 0.381 0.8382)
			(end -0.381 -0.8382)
			(stroke
				(width 0)
				(type default)
			)
			(fill no)
			(layer "B.CrtYd")
		)
		(fp_rect
			(start 0.381 0.8382)
			(end -0.381 -0.8382)
			(stroke
				(width 0)
				(type default)
			)
			(fill no)
			(layer "B.Fab")
		)
		(pad "1" smd custom
			(at 0 -0.4318 270)
			(size 0.127 0.127)
			(layers "B.Cu" "B.Mask" "B.Paste")
			(net "P3V3")
			(options
				(clearance outline)
				(anchor circle)
			)
			(primitives
				(gr_poly
					(pts
						(arc
							(start -0.2032 0.2794)
							(mid -0.239121 0.264521)
							(end -0.254 0.2286)
						)
						(arc
							(start -0.254 -0.2286)
							(mid -0.239121 -0.264521)
							(end -0.2032 -0.2794)
						)
						(arc
							(start 0.2032 -0.2794)
							(mid 0.239121 -0.264521)
							(end 0.254 -0.2286)
						)
						(arc
							(start 0.254 0.2286)
							(mid 0.239121 0.264521)
							(end 0.2032 0.2794)
						)
					)
					(width 0)
					(fill yes)
				)
			)
		)
		(pad "2" smd custom
			(at 0 0.4318 270)
			(size 0.127 0.127)
			(layers "B.Cu" "B.Mask" "B.Paste")
			(net "FLEX_CLK_SE0")
			(options
				(clearance outline)
				(anchor circle)
			)
			(primitives
				(gr_poly
					(pts
						(arc
							(start -0.2032 0.2794)
							(mid -0.239121 0.264521)
							(end -0.254 0.2286)
						)
						(arc
							(start -0.254 -0.2286)
							(mid -0.239121 -0.264521)
							(end -0.2032 -0.2794)
						)
						(arc
							(start 0.2032 -0.2794)
							(mid 0.239121 -0.264521)
							(end 0.254 -0.2286)
						)
						(arc
							(start 0.254 0.2286)
							(mid 0.239121 0.264521)
							(end 0.2032 0.2794)
						)
					)
					(width 0)
					(fill yes)
				)
			)
		)
	)
)
